(kicad_pcb
	(version 20260206)
	(generator "pcbnew")
	(generator_version "10.0")
	(general
		(thickness 1.6)
		(legacy_teardrops no)
	)
	(paper "A4")
	(title_block
		(title "panther-plus-userver — 13130-1b_20150205.brd")
		(comment 1 "Honey Badger (Wiwynn) / footprint 624 of 1509 (DIMM4), pads 121-127 of 210")
	)
	(layers
		(0 "F.Cu" signal "TOP")
		(4 "In1.Cu" signal "L2")
		(6 "In2.Cu" signal "L3")
		(8 "In3.Cu" signal "L4")
		(10 "In4.Cu" signal "L5")
		(12 "In5.Cu" signal "L6")
		(14 "In6.Cu" signal "L7")
		(16 "In7.Cu" signal "L8")
		(18 "In8.Cu" signal "L9")
		(20 "In9.Cu" signal "L10")
		(22 "In10.Cu" signal "L11")
		(2 "B.Cu" signal "BOTTOM")
		(9 "F.Adhes" user "F.Adhesive")
		(11 "B.Adhes" user "B.Adhesive")
		(13 "F.Paste" user "Package Geometry/Pastemask Top")
		(15 "B.Paste" user "Package Geometry/Pastemask Bottom")
		(5 "F.SilkS" user "Ref Des/Silkscreen Top")
		(7 "B.SilkS" user "Ref Des/Silkscreen Bottom")
		(1 "F.Mask" user "Board Geometry/Soldermask Top")
		(3 "B.Mask" user "Board Geometry/Soldermask Bottom")
		(17 "Dwgs.User" user "User.Drawings")
		(19 "Cmts.User" user "User.Comments")
		(21 "Eco1.User" user "User.Eco1")
		(23 "Eco2.User" user "User.Eco2")
		(25 "Edge.Cuts" user "Board Geometry/Outline")
		(27 "Margin" user)
		(31 "F.CrtYd" user "Package Geometry/Place Bound Top")
		(29 "B.CrtYd" user "Package Geometry/Place Bound Bottom")
		(35 "F.Fab" user "Ref Des/Assembly Top")
		(33 "B.Fab" user "Ref Des/Assembly Bottom")
	)
	(footprint ""
		(layer "F.Cu")
		(at 159.999934 -5.790692)
		(property "Reference" "DIMM4"
			(at 0 0 0)
			(layer "F.SilkS")
			(hide yes)
			(effects
				(font
					(size 1.27 1.27)
				)
			)
		)
		(property "Value" "DDR3-204P-174-COLAY-1-GP"
			(at -40.682164 -17.468088 0)
			(unlocked yes)
			(layer "F.Fab")
			(hide yes)
			(effects
				(font
					(size 1.016 1.016)
					(thickness 0.1524)
				)
			)
		)
		(property "Device Type" "AS0A626-H8SN-7H-COLAY-1"
			(at -40.682164 -18.992088 0)
			(unlocked yes)
			(layer "F.Fab")
			(hide yes)
			(effects
				(font
					(size 1.016 1.016)
					(thickness 0.1524)
				)
			)
		)
		(duplicate_pad_numbers_are_jumpers no)
		(pad "119" smd custom
			(at 6.150102 4.106672)
			(size 0.1143 0.1143)
			(layers "F.Cu" "F.Mask" "F.Paste")
			(net "M_B_BS0")
			(options
				(clearance outline)
				(anchor circle)
			)
			(primitives
				(gr_poly
					(pts
						(xy 0 0.9017) (xy -0.03175 0.89916) (xy -0.0635 0.889) (xy -0.09144 0.87376) (xy -0.11684 0.85344)
						(xy -0.13716 0.82804) (xy -0.1524 0.8001) (xy -0.16256 0.76835) (xy -0.1651 0.7366) (xy -0.1651 0.11938)
						(xy -0.17272 0.11176) (xy -0.19812 0.0762) (xy -0.2032 0.06604) (xy -0.20701 0.05715) (xy -0.21209 0.04699)
						(xy -0.2159 0.03683) (xy -0.21844 0.02667) (xy -0.22225 0.01524) (xy -0.22352 0.00508) (xy -0.22606 -0.00508)
						(xy -0.22733 -0.01651) (xy -0.22733 -0.02667) (xy -0.2286 -0.0381) (xy -0.22733 -0.04953) (xy -0.22733 -0.05969)
						(xy -0.22606 -0.07112) (xy -0.22352 -0.08128) (xy -0.22225 -0.09144) (xy -0.21844 -0.10287) (xy -0.2159 -0.11303)
						(xy -0.21209 -0.12319) (xy -0.20701 -0.13335) (xy -0.2032 -0.14224) (xy -0.19812 -0.1524) (xy -0.17272 -0.18796)
						(xy -0.1651 -0.19558) (xy -0.1651 -0.7366) (xy -0.16256 -0.76835) (xy -0.1524 -0.8001) (xy -0.13716 -0.82804)
						(xy -0.11684 -0.85344) (xy -0.09144 -0.87376) (xy -0.0635 -0.889) (xy -0.03175 -0.89916) (xy 0 -0.9017)
						(xy 0.03175 -0.89916) (xy 0.0635 -0.889) (xy 0.09144 -0.87376) (xy 0.11684 -0.85344) (xy 0.13716 -0.82804)
						(xy 0.1524 -0.8001) (xy 0.16256 -0.76835) (xy 0.1651 -0.7366) (xy 0.1651 -0.19685) (xy 0.17272 -0.18923)
						(xy 0.17907 -0.18034) (xy 0.18669 -0.17145) (xy 0.19177 -0.16256) (xy 0.19812 -0.15367) (xy 0.20828 -0.13335)
						(xy 0.21971 -0.10287) (xy 0.22225 -0.09271) (xy 0.22479 -0.08128) (xy 0.22606 -0.07112) (xy 0.2286 -0.05969)
						(xy 0.2286 -0.01651) (xy 0.22606 -0.00508) (xy 0.22479 0.00508) (xy 0.22225 0.01651) (xy 0.21971 0.02667)
						(xy 0.20828 0.05715) (xy 0.19812 0.07747) (xy 0.19177 0.08636) (xy 0.18669 0.09525) (xy 0.17907 0.10414)
						(xy 0.17272 0.11303) (xy 0.1651 0.12065) (xy 0.1651 0.7366) (xy 0.16256 0.76835) (xy 0.1524 0.8001)
						(xy 0.13716 0.82804) (xy 0.11684 0.85344) (xy 0.09144 0.87376) (xy 0.0635 0.889) (xy 0.03175 0.89916)
					)
					(width 0)
					(fill yes)
				)
			)
		)
		(pad "120" smd custom
			(at 6.450076 -4.106672)
			(size 0.1143 0.1143)
			(layers "F.Cu" "F.Mask" "F.Paste")
			(net "Net_3")
			(options
				(clearance outline)
				(anchor circle)
			)
			(primitives
				(gr_poly
					(pts
						(xy 0 0.9017) (xy -0.03175 0.89916) (xy -0.0635 0.889) (xy -0.09144 0.87376) (xy -0.11684 0.85344)
						(xy -0.13716 0.82804) (xy -0.1524 0.8001) (xy -0.16256 0.76835) (xy -0.1651 0.7366) (xy -0.1651 0.19685)
						(xy -0.17272 0.18923) (xy -0.17907 0.18034) (xy -0.18669 0.17145) (xy -0.19177 0.16256) (xy -0.19812 0.15367)
						(xy -0.20828 0.13335) (xy -0.21971 0.10287) (xy -0.22225 0.09271) (xy -0.22479 0.08128) (xy -0.22606 0.07112)
						(xy -0.2286 0.05969) (xy -0.2286 0.01651) (xy -0.22606 0.00508) (xy -0.22479 -0.00508) (xy -0.22225 -0.01651)
						(xy -0.21971 -0.02667) (xy -0.20828 -0.05715) (xy -0.19812 -0.07747) (xy -0.19177 -0.08636) (xy -0.18669 -0.09525)
						(xy -0.17907 -0.10414) (xy -0.17272 -0.11303) (xy -0.1651 -0.12065) (xy -0.1651 -0.7366) (xy -0.16256 -0.76835)
						(xy -0.1524 -0.8001) (xy -0.13716 -0.82804) (xy -0.11684 -0.85344) (xy -0.09144 -0.87376) (xy -0.0635 -0.889)
						(xy -0.03175 -0.89916) (xy 0 -0.9017) (xy 0.03175 -0.89916) (xy 0.0635 -0.889) (xy 0.09144 -0.87376)
						(xy 0.11684 -0.85344) (xy 0.13716 -0.82804) (xy 0.1524 -0.8001) (xy 0.16256 -0.76835) (xy 0.1651 -0.7366)
						(xy 0.1651 -0.11938) (xy 0.17272 -0.11176) (xy 0.19812 -0.0762) (xy 0.2032 -0.06604) (xy 0.20701 -0.05715)
						(xy 0.21209 -0.04699) (xy 0.2159 -0.03683) (xy 0.21844 -0.02667) (xy 0.22225 -0.01524) (xy 0.22352 -0.00508)
						(xy 0.22606 0.00508) (xy 0.22733 0.01651) (xy 0.22733 0.02667) (xy 0.2286 0.0381) (xy 0.22733 0.04953)
						(xy 0.22733 0.05969) (xy 0.22606 0.07112) (xy 0.22352 0.08128) (xy 0.22225 0.09144) (xy 0.21844 0.10287)
						(xy 0.2159 0.11303) (xy 0.21209 0.12319) (xy 0.20701 0.13335) (xy 0.2032 0.14224) (xy 0.19812 0.1524)
						(xy 0.17272 0.18796) (xy 0.1651 0.19558) (xy 0.1651 0.7366) (xy 0.16256 0.76835) (xy 0.1524 0.8001)
						(xy 0.13716 0.82804) (xy 0.11684 0.85344) (xy 0.09144 0.87376) (xy 0.0635 0.889) (xy 0.03175 0.89916)
					)
					(width 0)
					(fill yes)
				)
			)
		)
		(pad "121" smd custom
			(at 6.75005 4.106672)
			(size 0.1143 0.1143)
			(layers "F.Cu" "F.Mask" "F.Paste")
			(net "M_B_WE#")
			(options
				(clearance outline)
				(anchor circle)
			)
			(primitives
				(gr_poly
					(pts
						(xy 0 0.9017) (xy -0.03175 0.89916) (xy -0.0635 0.889) (xy -0.09144 0.87376) (xy -0.11684 0.85344)
						(xy -0.13716 0.82804) (xy -0.1524 0.8001) (xy -0.16256 0.76835) (xy -0.1651 0.7366) (xy -0.1651 -0.13462)
						(xy -0.17272 -0.14224) (xy -0.19812 -0.1778) (xy -0.2032 -0.18796) (xy -0.20701 -0.19685) (xy -0.21209 -0.20701)
						(xy -0.2159 -0.21717) (xy -0.21844 -0.22733) (xy -0.22225 -0.23876) (xy -0.22352 -0.24892) (xy -0.22606 -0.25908)
						(xy -0.22733 -0.27051) (xy -0.22733 -0.28067) (xy -0.2286 -0.2921) (xy -0.22733 -0.30353) (xy -0.22733 -0.31369)
						(xy -0.22606 -0.32512) (xy -0.22352 -0.33528) (xy -0.22225 -0.34544) (xy -0.21844 -0.35687) (xy -0.2159 -0.36703)
						(xy -0.21209 -0.37719) (xy -0.20701 -0.38735) (xy -0.2032 -0.39624) (xy -0.19812 -0.4064) (xy -0.17272 -0.44196)
						(xy -0.1651 -0.44958) (xy -0.1651 -0.7366) (xy -0.16256 -0.76835) (xy -0.1524 -0.8001) (xy -0.13716 -0.82804)
						(xy -0.11684 -0.85344) (xy -0.09144 -0.87376) (xy -0.0635 -0.889) (xy -0.03175 -0.89916) (xy 0 -0.9017)
						(xy 0.03175 -0.89916) (xy 0.0635 -0.889) (xy 0.09144 -0.87376) (xy 0.11684 -0.85344) (xy 0.13716 -0.82804)
						(xy 0.1524 -0.8001) (xy 0.16256 -0.76835) (xy 0.1651 -0.7366) (xy 0.1651 -0.44958) (xy 0.17272 -0.44196)
						(xy 0.19812 -0.4064) (xy 0.2032 -0.39624) (xy 0.20701 -0.38735) (xy 0.21209 -0.37719) (xy 0.2159 -0.36703)
						(xy 0.21844 -0.35687) (xy 0.22225 -0.34544) (xy 0.22352 -0.33528) (xy 0.22606 -0.32512) (xy 0.22733 -0.31369)
						(xy 0.22733 -0.30353) (xy 0.2286 -0.2921) (xy 0.22733 -0.28067) (xy 0.22733 -0.27051) (xy 0.22606 -0.25908)
						(xy 0.22352 -0.24892) (xy 0.22225 -0.23876) (xy 0.21844 -0.22733) (xy 0.2159 -0.21717) (xy 0.21209 -0.20701)
						(xy 0.20701 -0.19685) (xy 0.2032 -0.18796) (xy 0.19812 -0.1778) (xy 0.17272 -0.14224) (xy 0.1651 -0.13462)
						(xy 0.1651 0.7366) (xy 0.16256 0.76835) (xy 0.1524 0.8001) (xy 0.13716 0.82804) (xy 0.11684 0.85344)
						(xy 0.09144 0.87376) (xy 0.0635 0.889) (xy 0.03175 0.89916)
					)
					(width 0)
					(fill yes)
				)
			)
		)
		(pad "122" smd custom
			(at 7.050024 -4.106672)
			(size 0.1143 0.1143)
			(layers "F.Cu" "F.Mask" "F.Paste")
			(net "M_B_RAS#")
			(options
				(clearance outline)
				(anchor circle)
			)
			(primitives
				(gr_poly
					(pts
						(xy 0 0.9017) (xy -0.03175 0.89916) (xy -0.0635 0.889) (xy -0.09144 0.87376) (xy -0.11684 0.85344)
						(xy -0.13716 0.82804) (xy -0.1524 0.8001) (xy -0.16256 0.76835) (xy -0.1651 0.7366) (xy -0.1651 0.44958)
						(xy -0.17272 0.44196) (xy -0.19812 0.4064) (xy -0.2032 0.39624) (xy -0.20701 0.38735) (xy -0.21209 0.37719)
						(xy -0.2159 0.36703) (xy -0.21844 0.35687) (xy -0.22225 0.34544) (xy -0.22352 0.33528) (xy -0.22606 0.32512)
						(xy -0.22733 0.31369) (xy -0.22733 0.30353) (xy -0.2286 0.2921) (xy -0.22733 0.28067) (xy -0.22733 0.27051)
						(xy -0.22606 0.25908) (xy -0.22352 0.24892) (xy -0.22225 0.23876) (xy -0.21844 0.22733) (xy -0.2159 0.21717)
						(xy -0.21209 0.20701) (xy -0.20701 0.19685) (xy -0.2032 0.18796) (xy -0.19812 0.1778) (xy -0.17272 0.14224)
						(xy -0.1651 0.13462) (xy -0.1651 -0.7366) (xy -0.16256 -0.76835) (xy -0.1524 -0.8001) (xy -0.13716 -0.82804)
						(xy -0.11684 -0.85344) (xy -0.09144 -0.87376) (xy -0.0635 -0.889) (xy -0.03175 -0.89916) (xy 0 -0.9017)
						(xy 0.03175 -0.89916) (xy 0.0635 -0.889) (xy 0.09144 -0.87376) (xy 0.11684 -0.85344) (xy 0.13716 -0.82804)
						(xy 0.1524 -0.8001) (xy 0.16256 -0.76835) (xy 0.1651 -0.7366) (xy 0.1651 0.13462) (xy 0.17272 0.14224)
						(xy 0.19812 0.1778) (xy 0.2032 0.18796) (xy 0.20701 0.19685) (xy 0.21209 0.20701) (xy 0.2159 0.21717)
						(xy 0.21844 0.22733) (xy 0.22225 0.23876) (xy 0.22352 0.24892) (xy 0.22606 0.25908) (xy 0.22733 0.27051)
						(xy 0.22733 0.28067) (xy 0.2286 0.2921) (xy 0.22733 0.30353) (xy 0.22733 0.31369) (xy 0.22606 0.32512)
						(xy 0.22352 0.33528) (xy 0.22225 0.34544) (xy 0.21844 0.35687) (xy 0.2159 0.36703) (xy 0.21209 0.37719)
						(xy 0.20701 0.38735) (xy 0.2032 0.39624) (xy 0.19812 0.4064) (xy 0.17272 0.44196) (xy 0.1651 0.44958)
						(xy 0.1651 0.7366) (xy 0.16256 0.76835) (xy 0.1524 0.8001) (xy 0.13716 0.82804) (xy 0.11684 0.85344)
						(xy 0.09144 0.87376) (xy 0.0635 0.889) (xy 0.03175 0.89916)
					)
					(width 0)
					(fill yes)
				)
			)
		)
		(pad "123" smd custom
			(at 7.349998 4.106672)
			(size 0.1143 0.1143)
			(layers "F.Cu" "F.Mask" "F.Paste")
			(net "PV_VDDR")
			(options
				(clearance outline)
				(anchor circle)
			)
			(primitives
				(gr_poly
					(pts
						(xy 0 0.9017) (xy -0.03175 0.89916) (xy -0.0635 0.889) (xy -0.09144 0.87376) (xy -0.11684 0.85344)
						(xy -0.13716 0.82804) (xy -0.1524 0.8001) (xy -0.16256 0.76835) (xy -0.1651 0.7366) (xy -0.1651 0.11938)
						(xy -0.17272 0.11176) (xy -0.19812 0.0762) (xy -0.2032 0.06604) (xy -0.20701 0.05715) (xy -0.21209 0.04699)
						(xy -0.2159 0.03683) (xy -0.21844 0.02667) (xy -0.22225 0.01524) (xy -0.22352 0.00508) (xy -0.22606 -0.00508)
						(xy -0.22733 -0.01651) (xy -0.22733 -0.02667) (xy -0.2286 -0.0381) (xy -0.22733 -0.04953) (xy -0.22733 -0.05969)
						(xy -0.22606 -0.07112) (xy -0.22352 -0.08128) (xy -0.22225 -0.09144) (xy -0.21844 -0.10287) (xy -0.2159 -0.11303)
						(xy -0.21209 -0.12319) (xy -0.20701 -0.13335) (xy -0.2032 -0.14224) (xy -0.19812 -0.1524) (xy -0.17272 -0.18796)
						(xy -0.1651 -0.19558) (xy -0.1651 -0.7366) (xy -0.16256 -0.76835) (xy -0.1524 -0.8001) (xy -0.13716 -0.82804)
						(xy -0.11684 -0.85344) (xy -0.09144 -0.87376) (xy -0.0635 -0.889) (xy -0.03175 -0.89916) (xy 0 -0.9017)
						(xy 0.03175 -0.89916) (xy 0.0635 -0.889) (xy 0.09144 -0.87376) (xy 0.11684 -0.85344) (xy 0.13716 -0.82804)
						(xy 0.1524 -0.8001) (xy 0.16256 -0.76835) (xy 0.1651 -0.7366) (xy 0.1651 -0.19685) (xy 0.17272 -0.18923)
						(xy 0.17907 -0.18034) (xy 0.18669 -0.17145) (xy 0.19177 -0.16256) (xy 0.19812 -0.15367) (xy 0.20828 -0.13335)
						(xy 0.21971 -0.10287) (xy 0.22225 -0.09271) (xy 0.22479 -0.08128) (xy 0.22606 -0.07112) (xy 0.2286 -0.05969)
						(xy 0.2286 -0.01651) (xy 0.22606 -0.00508) (xy 0.22479 0.00508) (xy 0.22225 0.01651) (xy 0.21971 0.02667)
						(xy 0.20828 0.05715) (xy 0.19812 0.07747) (xy 0.19177 0.08636) (xy 0.18669 0.09525) (xy 0.17907 0.10414)
						(xy 0.17272 0.11303) (xy 0.1651 0.12065) (xy 0.1651 0.7366) (xy 0.16256 0.76835) (xy 0.1524 0.8001)
						(xy 0.13716 0.82804) (xy 0.11684 0.85344) (xy 0.09144 0.87376) (xy 0.0635 0.889) (xy 0.03175 0.89916)
					)
					(width 0)
					(fill yes)
				)
			)
		)
		(pad "124" smd custom
			(at 7.649972 -4.106672)
			(size 0.1143 0.1143)
			(layers "F.Cu" "F.Mask" "F.Paste")
			(net "PV_VDDR")
			(options
				(clearance outline)
				(anchor circle)
			)
			(primitives
				(gr_poly
					(pts
						(xy 0 0.9017) (xy -0.03175 0.89916) (xy -0.0635 0.889) (xy -0.09144 0.87376) (xy -0.11684 0.85344)
						(xy -0.13716 0.82804) (xy -0.1524 0.8001) (xy -0.16256 0.76835) (xy -0.1651 0.7366) (xy -0.1651 0.19685)
						(xy -0.17272 0.18923) (xy -0.17907 0.18034) (xy -0.18669 0.17145) (xy -0.19177 0.16256) (xy -0.19812 0.15367)
						(xy -0.20828 0.13335) (xy -0.21971 0.10287) (xy -0.22225 0.09271) (xy -0.22479 0.08128) (xy -0.22606 0.07112)
						(xy -0.2286 0.05969) (xy -0.2286 0.01651) (xy -0.22606 0.00508) (xy -0.22479 -0.00508) (xy -0.22225 -0.01651)
						(xy -0.21971 -0.02667) (xy -0.20828 -0.05715) (xy -0.19812 -0.07747) (xy -0.19177 -0.08636) (xy -0.18669 -0.09525)
						(xy -0.17907 -0.10414) (xy -0.17272 -0.11303) (xy -0.1651 -0.12065) (xy -0.1651 -0.7366) (xy -0.16256 -0.76835)
						(xy -0.1524 -0.8001) (xy -0.13716 -0.82804) (xy -0.11684 -0.85344) (xy -0.09144 -0.87376) (xy -0.0635 -0.889)
						(xy -0.03175 -0.89916) (xy 0 -0.9017) (xy 0.03175 -0.89916) (xy 0.0635 -0.889) (xy 0.09144 -0.87376)
						(xy 0.11684 -0.85344) (xy 0.13716 -0.82804) (xy 0.1524 -0.8001) (xy 0.16256 -0.76835) (xy 0.1651 -0.7366)
						(xy 0.1651 -0.11938) (xy 0.17272 -0.11176) (xy 0.19812 -0.0762) (xy 0.2032 -0.06604) (xy 0.20701 -0.05715)
						(xy 0.21209 -0.04699) (xy 0.2159 -0.03683) (xy 0.21844 -0.02667) (xy 0.22225 -0.01524) (xy 0.22352 -0.00508)
						(xy 0.22606 0.00508) (xy 0.22733 0.01651) (xy 0.22733 0.02667) (xy 0.2286 0.0381) (xy 0.22733 0.04953)
						(xy 0.22733 0.05969) (xy 0.22606 0.07112) (xy 0.22352 0.08128) (xy 0.22225 0.09144) (xy 0.21844 0.10287)
						(xy 0.2159 0.11303) (xy 0.21209 0.12319) (xy 0.20701 0.13335) (xy 0.2032 0.14224) (xy 0.19812 0.1524)
						(xy 0.17272 0.18796) (xy 0.1651 0.19558) (xy 0.1651 0.7366) (xy 0.16256 0.76835) (xy 0.1524 0.8001)
						(xy 0.13716 0.82804) (xy 0.11684 0.85344) (xy 0.09144 0.87376) (xy 0.0635 0.889) (xy 0.03175 0.89916)
					)
					(width 0)
					(fill yes)
				)
			)
		)
		(pad "125" smd custom
			(at 7.949946 4.106672)
			(size 0.1143 0.1143)
			(layers "F.Cu" "F.Mask" "F.Paste")
			(net "M_B_CAS#")
			(options
				(clearance outline)
				(anchor circle)
			)
			(primitives
				(gr_poly
					(pts
						(xy 0 0.9017) (xy -0.03175 0.89916) (xy -0.0635 0.889) (xy -0.09144 0.87376) (xy -0.11684 0.85344)
						(xy -0.13716 0.82804) (xy -0.1524 0.8001) (xy -0.16256 0.76835) (xy -0.1651 0.7366) (xy -0.1651 -0.13462)
						(xy -0.17272 -0.14224) (xy -0.19812 -0.1778) (xy -0.2032 -0.18796) (xy -0.20701 -0.19685) (xy -0.21209 -0.20701)
						(xy -0.2159 -0.21717) (xy -0.21844 -0.22733) (xy -0.22225 -0.23876) (xy -0.22352 -0.24892) (xy -0.22606 -0.25908)
						(xy -0.22733 -0.27051) (xy -0.22733 -0.28067) (xy -0.2286 -0.2921) (xy -0.22733 -0.30353) (xy -0.22733 -0.31369)
						(xy -0.22606 -0.32512) (xy -0.22352 -0.33528) (xy -0.22225 -0.34544) (xy -0.21844 -0.35687) (xy -0.2159 -0.36703)
						(xy -0.21209 -0.37719) (xy -0.20701 -0.38735) (xy -0.2032 -0.39624) (xy -0.19812 -0.4064) (xy -0.17272 -0.44196)
						(xy -0.1651 -0.44958) (xy -0.1651 -0.7366) (xy -0.16256 -0.76835) (xy -0.1524 -0.8001) (xy -0.13716 -0.82804)
						(xy -0.11684 -0.85344) (xy -0.09144 -0.87376) (xy -0.0635 -0.889) (xy -0.03175 -0.89916) (xy 0 -0.9017)
						(xy 0.03175 -0.89916) (xy 0.0635 -0.889) (xy 0.09144 -0.87376) (xy 0.11684 -0.85344) (xy 0.13716 -0.82804)
						(xy 0.1524 -0.8001) (xy 0.16256 -0.76835) (xy 0.1651 -0.7366) (xy 0.1651 -0.44958) (xy 0.17272 -0.44196)
						(xy 0.19812 -0.4064) (xy 0.2032 -0.39624) (xy 0.20701 -0.38735) (xy 0.21209 -0.37719) (xy 0.2159 -0.36703)
						(xy 0.21844 -0.35687) (xy 0.22225 -0.34544) (xy 0.22352 -0.33528) (xy 0.22606 -0.32512) (xy 0.22733 -0.31369)
						(xy 0.22733 -0.30353) (xy 0.2286 -0.2921) (xy 0.22733 -0.28067) (xy 0.22733 -0.27051) (xy 0.22606 -0.25908)
						(xy 0.22352 -0.24892) (xy 0.22225 -0.23876) (xy 0.21844 -0.22733) (xy 0.2159 -0.21717) (xy 0.21209 -0.20701)
						(xy 0.20701 -0.19685) (xy 0.2032 -0.18796) (xy 0.19812 -0.1778) (xy 0.17272 -0.14224) (xy 0.1651 -0.13462)
						(xy 0.1651 0.7366) (xy 0.16256 0.76835) (xy 0.1524 0.8001) (xy 0.13716 0.82804) (xy 0.11684 0.85344)
						(xy 0.09144 0.87376) (xy 0.0635 0.889) (xy 0.03175 0.89916)
					)
					(width 0)
					(fill yes)
				)
			)
		)
	)
)
